# S9S_MB_2U (Grand Teton) — schematic netlist excerpt (pin names and nets, part order shuffled) for the footprints in the layout excerpt that follows; sources: Cadence DE-HDL packaged netlist, KiCad conversion of 03242023_DA0F0TMBIJ0_F0T_Motherboard_J_brd_V01_OCP.brd

R1415  Q_RES  2K 1% EMPTY  pkg 0402LF  page 219 : A = RST_CPU0_LVC1_R_N ; B = GND
R1342  Q_RES  10K 1% CHIP  pkg 0402LF  page 201 : A = P1V05_PCH_AUX ; B = FM_ME_RCVR_N

(kicad_pcb
	(version 20260206)
	(generator "pcbnew")
	(generator_version "10.0")
	(general
		(thickness 1.6)
		(legacy_teardrops no)
	)
	(paper "A4")
	(title_block
		(title "03242023_DA0F0TMBIJ0_F0T_Motherboard_J_brd_V01_OCP.brd")
		(comment 1 "Grand Teton / footprints 2794-2795 of 6105")
	)
	(layers
		(0 "F.Cu" signal "TOP")
		(4 "In1.Cu" signal "GND")
		(6 "In2.Cu" signal "IN1")
		(8 "In3.Cu" signal "GND1")
		(10 "In4.Cu" signal "IN2")
		(12 "In5.Cu" signal "GND2")
		(14 "In6.Cu" signal "IN3")
		(16 "In7.Cu" signal "GND3")
		(18 "In8.Cu" signal "VCC")
		(20 "In9.Cu" signal "VCC1")
		(22 "In10.Cu" signal "GND4")
		(24 "In11.Cu" signal "IN4")
		(26 "In12.Cu" signal "GND5")
		(28 "In13.Cu" signal "IN5")
		(30 "In14.Cu" signal "GND6")
		(32 "In15.Cu" signal "IN6")
		(34 "In16.Cu" signal "GND7")
		(2 "B.Cu" signal "BOTTOM")
		(9 "F.Adhes" user "F.Adhesive")
		(11 "B.Adhes" user "B.Adhesive")
		(13 "F.Paste" user "Package Geometry/Pastemask Top")
		(15 "B.Paste" user "Package Geometry/Pastemask Bottom")
		(5 "F.SilkS" user "Ref Des/Silkscreen Top")
		(7 "B.SilkS" user "Ref Des/Silkscreen Bottom")
		(1 "F.Mask" user "Board Geometry/Soldermask Top")
		(3 "B.Mask" user "Board Geometry/Soldermask Bottom")
		(17 "Dwgs.User" user "User.Drawings")
		(19 "Cmts.User" user "User.Comments")
		(21 "Eco1.User" user "User.Eco1")
		(23 "Eco2.User" user "User.Eco2")
		(25 "Edge.Cuts" user "Board Geometry/Outline")
		(27 "Margin" user)
		(31 "F.CrtYd" user "Package Geometry/Place Bound Top")
		(29 "B.CrtYd" user "Package Geometry/Place Bound Bottom")
		(35 "F.Fab" user "Ref Des/Assembly Top")
		(33 "B.Fab" user "Ref Des/Assembly Bottom")
	)
	(footprint ""
		(layer "F.Cu")
		(at 300.094904 -41.987724 -90)
		(property "Reference" "R1342"
			(at 0 0 270)
			(layer "F.SilkS")
			(hide yes)
			(effects
				(font
					(size 1.27 1.27)
				)
			)
		)
		(property "Value" ""
			(at 0 0 270)
			(layer "F.Fab")
			(effects
				(font
					(size 1.27 1.27)
				)
			)
		)
		(duplicate_pad_numbers_are_jumpers no)
		(fp_line
			(start -0.7874 0.4064)
			(end -0.7874 -0.4064)
			(stroke
				(width 0.1524)
				(type default)
			)
			(layer "F.SilkS")
		)
		(fp_line
			(start 0.7874 0.4064)
			(end -0.7874 0.4064)
			(stroke
				(width 0.1524)
				(type default)
			)
			(layer "F.SilkS")
		)
		(fp_line
			(start -0.7874 -0.4064)
			(end 0.7874 -0.4064)
			(stroke
				(width 0.1524)
				(type default)
			)
			(layer "F.SilkS")
		)
		(fp_line
			(start 0.7874 -0.4064)
			(end 0.7874 0.4064)
			(stroke
				(width 0.1524)
				(type default)
			)
			(layer "F.SilkS")
		)
		(fp_line
			(start -0.67945 0.3048)
			(end -0.67945 -0.305054)
			(stroke
				(width 0.1)
				(type default)
			)
			(layer "F.Fab")
		)
		(fp_line
			(start -0.12065 0.3048)
			(end -0.67945 0.3048)
			(stroke
				(width 0.1)
				(type default)
			)
			(layer "F.Fab")
		)
		(fp_line
			(start 0.120396 0.3048)
			(end 0.120396 0.2794)
			(stroke
				(width 0.1)
				(type default)
			)
			(layer "F.Fab")
		)
		(fp_line
			(start 0.67945 0.3048)
			(end 0.120396 0.3048)
			(stroke
				(width 0.1)
				(type default)
			)
			(layer "F.Fab")
		)
		(fp_line
			(start -0.12065 0.2794)
			(end -0.12065 0.3048)
			(stroke
				(width 0.1)
				(type default)
			)
			(layer "F.Fab")
		)
		(fp_line
			(start 0.120396 0.2794)
			(end -0.12065 0.2794)
			(stroke
				(width 0.1)
				(type default)
			)
			(layer "F.Fab")
		)
		(fp_line
			(start -0.12065 -0.2794)
			(end 0.12065 -0.2794)
			(stroke
				(width 0.1)
				(type default)
			)
			(layer "F.Fab")
		)
		(fp_line
			(start 0.12065 -0.2794)
			(end 0.12065 -0.3048)
			(stroke
				(width 0.1)
				(type default)
			)
			(layer "F.Fab")
		)
		(fp_line
			(start 0.12065 -0.3048)
			(end 0.67945 -0.3048)
			(stroke
				(width 0.1)
				(type default)
			)
			(layer "F.Fab")
		)
		(fp_line
			(start 0.67945 -0.3048)
			(end 0.67945 0.3048)
			(stroke
				(width 0.1)
				(type default)
			)
			(layer "F.Fab")
		)
		(fp_line
			(start -0.67945 -0.305054)
			(end -0.12065 -0.305054)
			(stroke
				(width 0.1)
				(type default)
			)
			(layer "F.Fab")
		)
		(fp_line
			(start -0.12065 -0.305054)
			(end -0.12065 -0.2794)
			(stroke
				(width 0.1)
				(type default)
			)
			(layer "F.Fab")
		)
		(pad "1" smd circle
			(at -0.40005 0 270)
			(size 0 0)
			(layers "F.Cu" "F.Mask" "F.Paste")
			(net "P1V05_PCH_AUX")
		)
		(pad "2" smd circle
			(at 0.40005 0 270)
			(size 0 0)
			(layers "F.Cu" "F.Mask" "F.Paste")
			(net "FM_ME_RCVR_N")
		)
	)
	(footprint ""
		(layer "F.Cu")
		(at 182.42788 -99.659948 -90)
		(property "Reference" "R1415"
			(at 0 0 270)
			(layer "F.SilkS")
			(hide yes)
			(effects
				(font
					(size 1.27 1.27)
				)
			)
		)
		(property "Value" ""
			(at 0 0 270)
			(layer "F.Fab")
			(effects
				(font
					(size 1.27 1.27)
				)
			)
		)
		(duplicate_pad_numbers_are_jumpers no)
		(fp_line
			(start -0.7874 0.4064)
			(end -0.7874 -0.4064)
			(stroke
				(width 0.1524)
				(type default)
			)
			(layer "F.SilkS")
		)
		(fp_line
			(start 0.7874 0.4064)
			(end -0.7874 0.4064)
			(stroke
				(width 0.1524)
				(type default)
			)
			(layer "F.SilkS")
		)
		(fp_line
			(start -0.7874 -0.4064)
			(end 0.7874 -0.4064)
			(stroke
				(width 0.1524)
				(type default)
			)
			(layer "F.SilkS")
		)
		(fp_line
			(start 0.7874 -0.4064)
			(end 0.7874 0.4064)
			(stroke
				(width 0.1524)
				(type default)
			)
			(layer "F.SilkS")
		)
		(fp_line
			(start -0.67945 0.3048)
			(end -0.67945 -0.305054)
			(stroke
				(width 0.1)
				(type default)
			)
			(layer "F.Fab")
		)
		(fp_line
			(start -0.12065 0.3048)
			(end -0.67945 0.3048)
			(stroke
				(width 0.1)
				(type default)
			)
			(layer "F.Fab")
		)
		(fp_line
			(start 0.120396 0.3048)
			(end 0.120396 0.2794)
			(stroke
				(width 0.1)
				(type default)
			)
			(layer "F.Fab")
		)
		(fp_line
			(start 0.67945 0.3048)
			(end 0.120396 0.3048)
			(stroke
				(width 0.1)
				(type default)
			)
			(layer "F.Fab")
		)
		(fp_line
			(start -0.12065 0.2794)
			(end -0.12065 0.3048)
			(stroke
				(width 0.1)
				(type default)
			)
			(layer "F.Fab")
		)
		(fp_line
			(start 0.120396 0.2794)
			(end -0.12065 0.2794)
			(stroke
				(width 0.1)
				(type default)
			)
			(layer "F.Fab")
		)
		(fp_line
			(start -0.12065 -0.2794)
			(end 0.12065 -0.2794)
			(stroke
				(width 0.1)
				(type default)
			)
			(layer "F.Fab")
		)
		(fp_line
			(start 0.12065 -0.2794)
			(end 0.12065 -0.3048)
			(stroke
				(width 0.1)
				(type default)
			)
			(layer "F.Fab")
		)
		(fp_line
			(start 0.12065 -0.3048)
			(end 0.67945 -0.3048)
			(stroke
				(width 0.1)
				(type default)
			)
			(layer "F.Fab")
		)
		(fp_line
			(start 0.67945 -0.3048)
			(end 0.67945 0.3048)
			(stroke
				(width 0.1)
				(type default)
			)
			(layer "F.Fab")
		)
		(fp_line
			(start -0.67945 -0.305054)
			(end -0.12065 -0.305054)
			(stroke
				(width 0.1)
				(type default)
			)
			(layer "F.Fab")
		)
		(fp_line
			(start -0.12065 -0.305054)
			(end -0.12065 -0.2794)
			(stroke
				(width 0.1)
				(type default)
			)
			(layer "F.Fab")
		)
		(pad "1" smd circle
			(at -0.40005 0 270)
			(size 0 0)
			(layers "F.Cu" "F.Mask" "F.Paste")
			(net "RST_CPU0_LVC1_R_N")
		)
		(pad "2" smd circle
			(at 0.40005 0 270)
			(size 0 0)
			(layers "F.Cu" "F.Mask" "F.Paste")
			(net "GND")
		)
	)
)
